# S9S_MB_2U (Grand Teton) — schematic netlist excerpt (pin names and nets, part order shuffled) for the footprints in the layout excerpt that follows; sources: Cadence DE-HDL packaged netlist, KiCad conversion of 03242023_DA0F0TMBIJ0_F0T_Motherboard_J_brd_V01_OCP.brd

PR831  Q_RES  47K 0.1% CHIP  pkg 0402LF  page 259 : A = P3V3_AUX_FB ; B = P3V3_AUX
R2985  Q_RES  10K 1% CHIP  pkg 0402LF  page 231 : A = P3V3_AUX ; B = SMB_BMC_SWB_SDA

(kicad_pcb
	(version 20260206)
	(generator "pcbnew")
	(generator_version "10.0")
	(general
		(thickness 1.6)
		(legacy_teardrops no)
	)
	(paper "A4")
	(title_block
		(title "03242023_DA0F0TMBIJ0_F0T_Motherboard_J_brd_V01_OCP.brd")
		(comment 1 "Grand Teton / footprints 572-573 of 6105")
	)
	(layers
		(0 "F.Cu" signal "TOP")
		(4 "In1.Cu" signal "GND")
		(6 "In2.Cu" signal "IN1")
		(8 "In3.Cu" signal "GND1")
		(10 "In4.Cu" signal "IN2")
		(12 "In5.Cu" signal "GND2")
		(14 "In6.Cu" signal "IN3")
		(16 "In7.Cu" signal "GND3")
		(18 "In8.Cu" signal "VCC")
		(20 "In9.Cu" signal "VCC1")
		(22 "In10.Cu" signal "GND4")
		(24 "In11.Cu" signal "IN4")
		(26 "In12.Cu" signal "GND5")
		(28 "In13.Cu" signal "IN5")
		(30 "In14.Cu" signal "GND6")
		(32 "In15.Cu" signal "IN6")
		(34 "In16.Cu" signal "GND7")
		(2 "B.Cu" signal "BOTTOM")
		(9 "F.Adhes" user "F.Adhesive")
		(11 "B.Adhes" user "B.Adhesive")
		(13 "F.Paste" user "Package Geometry/Pastemask Top")
		(15 "B.Paste" user "Package Geometry/Pastemask Bottom")
		(5 "F.SilkS" user "Ref Des/Silkscreen Top")
		(7 "B.SilkS" user "Ref Des/Silkscreen Bottom")
		(1 "F.Mask" user "Board Geometry/Soldermask Top")
		(3 "B.Mask" user "Board Geometry/Soldermask Bottom")
		(17 "Dwgs.User" user "User.Drawings")
		(19 "Cmts.User" user "User.Comments")
		(21 "Eco1.User" user "User.Eco1")
		(23 "Eco2.User" user "User.Eco2")
		(25 "Edge.Cuts" user "Board Geometry/Outline")
		(27 "Margin" user)
		(31 "F.CrtYd" user "Package Geometry/Place Bound Top")
		(29 "B.CrtYd" user "Package Geometry/Place Bound Bottom")
		(35 "F.Fab" user "Ref Des/Assembly Top")
		(33 "B.Fab" user "Ref Des/Assembly Bottom")
	)
	(footprint ""
		(layer "F.Cu")
		(at 448.478402 -77.829918 90)
		(property "Reference" "PR831"
			(at 0 0 90)
			(layer "F.SilkS")
			(hide yes)
			(effects
				(font
					(size 1.27 1.27)
				)
			)
		)
		(property "Value" ""
			(at 0 0 90)
			(layer "F.Fab")
			(effects
				(font
					(size 1.27 1.27)
				)
			)
		)
		(duplicate_pad_numbers_are_jumpers no)
		(fp_line
			(start 0.7874 -0.4064)
			(end 0.7874 0.4064)
			(stroke
				(width 0.1524)
				(type default)
			)
			(layer "F.SilkS")
		)
		(fp_line
			(start -0.7874 -0.4064)
			(end 0.7874 -0.4064)
			(stroke
				(width 0.1524)
				(type default)
			)
			(layer "F.SilkS")
		)
		(fp_line
			(start 0.7874 0.4064)
			(end -0.7874 0.4064)
			(stroke
				(width 0.1524)
				(type default)
			)
			(layer "F.SilkS")
		)
		(fp_line
			(start -0.7874 0.4064)
			(end -0.7874 -0.4064)
			(stroke
				(width 0.1524)
				(type default)
			)
			(layer "F.SilkS")
		)
		(fp_line
			(start -0.12065 -0.305054)
			(end -0.12065 -0.2794)
			(stroke
				(width 0.1)
				(type default)
			)
			(layer "F.Fab")
		)
		(fp_line
			(start -0.67945 -0.305054)
			(end -0.12065 -0.305054)
			(stroke
				(width 0.1)
				(type default)
			)
			(layer "F.Fab")
		)
		(fp_line
			(start 0.67945 -0.3048)
			(end 0.67945 0.3048)
			(stroke
				(width 0.1)
				(type default)
			)
			(layer "F.Fab")
		)
		(fp_line
			(start 0.12065 -0.3048)
			(end 0.67945 -0.3048)
			(stroke
				(width 0.1)
				(type default)
			)
			(layer "F.Fab")
		)
		(fp_line
			(start 0.12065 -0.2794)
			(end 0.12065 -0.3048)
			(stroke
				(width 0.1)
				(type default)
			)
			(layer "F.Fab")
		)
		(fp_line
			(start -0.12065 -0.2794)
			(end 0.12065 -0.2794)
			(stroke
				(width 0.1)
				(type default)
			)
			(layer "F.Fab")
		)
		(fp_line
			(start 0.120396 0.2794)
			(end -0.12065 0.2794)
			(stroke
				(width 0.1)
				(type default)
			)
			(layer "F.Fab")
		)
		(fp_line
			(start -0.12065 0.2794)
			(end -0.12065 0.3048)
			(stroke
				(width 0.1)
				(type default)
			)
			(layer "F.Fab")
		)
		(fp_line
			(start 0.67945 0.3048)
			(end 0.120396 0.3048)
			(stroke
				(width 0.1)
				(type default)
			)
			(layer "F.Fab")
		)
		(fp_line
			(start 0.120396 0.3048)
			(end 0.120396 0.2794)
			(stroke
				(width 0.1)
				(type default)
			)
			(layer "F.Fab")
		)
		(fp_line
			(start -0.12065 0.3048)
			(end -0.67945 0.3048)
			(stroke
				(width 0.1)
				(type default)
			)
			(layer "F.Fab")
		)
		(fp_line
			(start -0.67945 0.3048)
			(end -0.67945 -0.305054)
			(stroke
				(width 0.1)
				(type default)
			)
			(layer "F.Fab")
		)
		(pad "1" smd circle
			(at -0.40005 0 90)
			(size 0 0)
			(layers "F.Cu" "F.Mask" "F.Paste")
			(net "P3V3_AUX_FB")
		)
		(pad "2" smd circle
			(at 0.40005 0 90)
			(size 0 0)
			(layers "F.Cu" "F.Mask" "F.Paste")
			(net "P3V3_AUX")
		)
	)
	(footprint ""
		(layer "F.Cu")
		(at 131.466844 -127.119126 180)
		(property "Reference" "R2985"
			(at 0 0 180)
			(layer "F.SilkS")
			(hide yes)
			(effects
				(font
					(size 1.27 1.27)
				)
			)
		)
		(property "Value" ""
			(at 0 0 180)
			(layer "F.Fab")
			(effects
				(font
					(size 1.27 1.27)
				)
			)
		)
		(duplicate_pad_numbers_are_jumpers no)
		(fp_line
			(start 0.7874 0.4064)
			(end -0.7874 0.4064)
			(stroke
				(width 0.1524)
				(type default)
			)
			(layer "F.SilkS")
		)
		(fp_line
			(start 0.7874 -0.4064)
			(end 0.7874 0.4064)
			(stroke
				(width 0.1524)
				(type default)
			)
			(layer "F.SilkS")
		)
		(fp_line
			(start -0.7874 0.4064)
			(end -0.7874 -0.4064)
			(stroke
				(width 0.1524)
				(type default)
			)
			(layer "F.SilkS")
		)
		(fp_line
			(start -0.7874 -0.4064)
			(end 0.7874 -0.4064)
			(stroke
				(width 0.1524)
				(type default)
			)
			(layer "F.SilkS")
		)
		(fp_line
			(start 0.67945 0.3048)
			(end 0.120396 0.3048)
			(stroke
				(width 0.1)
				(type default)
			)
			(layer "F.Fab")
		)
		(fp_line
			(start 0.67945 -0.3048)
			(end 0.67945 0.3048)
			(stroke
				(width 0.1)
				(type default)
			)
			(layer "F.Fab")
		)
		(fp_line
			(start 0.12065 -0.2794)
			(end 0.12065 -0.3048)
			(stroke
				(width 0.1)
				(type default)
			)
			(layer "F.Fab")
		)
		(fp_line
			(start 0.12065 -0.3048)
			(end 0.67945 -0.3048)
			(stroke
				(width 0.1)
				(type default)
			)
			(layer "F.Fab")
		)
		(fp_line
			(start 0.120396 0.3048)
			(end 0.120396 0.2794)
			(stroke
				(width 0.1)
				(type default)
			)
			(layer "F.Fab")
		)
		(fp_line
			(start 0.120396 0.2794)
			(end -0.12065 0.2794)
			(stroke
				(width 0.1)
				(type default)
			)
			(layer "F.Fab")
		)
		(fp_line
			(start -0.12065 0.3048)
			(end -0.67945 0.3048)
			(stroke
				(width 0.1)
				(type default)
			)
			(layer "F.Fab")
		)
		(fp_line
			(start -0.12065 0.2794)
			(end -0.12065 0.3048)
			(stroke
				(width 0.1)
				(type default)
			)
			(layer "F.Fab")
		)
		(fp_line
			(start -0.12065 -0.2794)
			(end 0.12065 -0.2794)
			(stroke
				(width 0.1)
				(type default)
			)
			(layer "F.Fab")
		)
		(fp_line
			(start -0.12065 -0.305054)
			(end -0.12065 -0.2794)
			(stroke
				(width 0.1)
				(type default)
			)
			(layer "F.Fab")
		)
		(fp_line
			(start -0.67945 0.3048)
			(end -0.67945 -0.305054)
			(stroke
				(width 0.1)
				(type default)
			)
			(layer "F.Fab")
		)
		(fp_line
			(start -0.67945 -0.305054)
			(end -0.12065 -0.305054)
			(stroke
				(width 0.1)
				(type default)
			)
			(layer "F.Fab")
		)
		(pad "1" smd circle
			(at -0.40005 0 180)
			(size 0 0)
			(layers "F.Cu" "F.Mask" "F.Paste")
			(net "P3V3_AUX")
		)
		(pad "2" smd circle
			(at 0.40005 0 180)
			(size 0 0)
			(layers "F.Cu" "F.Mask" "F.Paste")
			(net "SMB_BMC_SWB_SDA")
		)
	)
)
